(kicad_pcb
	(version 20241229)
	(generator "pcbnew")
	(generator_version "9.0")
	(general
		(thickness 1.61)
		(legacy_teardrops no)
	)
	(paper "A3")
	(title_block
		(title "RDIMM DDR5 Tester")
		(date "2026-05-21")
		(rev "2.2.0")
		(company "Antmicro")
		(comment 9 "footprint 119 of 796 (U34), pads 330-394 of 676")
	)
	(layers
		(0 "F.Cu" signal)
		(4 "In1.Cu" power)
		(6 "In2.Cu" mixed)
		(8 "In3.Cu" power)
		(10 "In4.Cu" mixed)
		(12 "In5.Cu" power)
		(14 "In6.Cu" mixed)
		(16 "In7.Cu" power)
		(18 "In8.Cu" power)
		(20 "In9.Cu" mixed)
		(22 "In10.Cu" power)
		(2 "B.Cu" signal)
		(9 "F.Adhes" user "F.Adhesive")
		(11 "B.Adhes" user "B.Adhesive")
		(13 "F.Paste" user)
		(15 "B.Paste" user)
		(5 "F.SilkS" user "F.Silkscreen")
		(7 "B.SilkS" user "B.Silkscreen")
		(1 "F.Mask" user)
		(3 "B.Mask" user)
		(17 "Dwgs.User" user "User.Drawings")
		(19 "Cmts.User" user "User.Comments")
		(21 "Eco1.User" user "User.Eco1")
		(23 "Eco2.User" user "User.Eco2")
		(25 "Edge.Cuts" user)
		(27 "Margin" user)
		(31 "F.CrtYd" user "F.Courtyard")
		(29 "B.CrtYd" user "B.Courtyard")
		(35 "F.Fab" user)
		(33 "B.Fab" user)
	)
	(footprint "antmicro-footprints:BGA-676_27x27mm_Layout26x26_P1x1mm_FFVB676"
		(layer "F.Cu")
		(at 188.5 152.5 90)
		(property "Reference" "U34"
			(at -14.72 12.46 180)
			(layer "F.SilkS")
			(effects
				(font
					(size 0.7 0.7)
					(thickness 0.15)
				)
				(justify left bottom)
			)
		)
		(property "Value" "XCAU25P-2FFVB676I"
			(at 0 15.5 90)
			(layer "F.Fab")
			(effects
				(font
					(size 0.7 0.7)
					(thickness 0.15)
				)
				(justify left bottom)
			)
		)
		(property "Datasheet" "https://docs.xilinx.com/viewer/book-attachment/2PXOpPtpaABIt0fkzeBLnw/hvbsEUaOT0OxFhln7VEVyA"
			(at 0 0 90)
			(layer "F.Fab")
			(hide yes)
			(effects
				(font
					(size 1.27 1.27)
					(thickness 0.15)
				)
			)
		)
		(property "MPN" "XCAU25P-2FFVB676I"
			(at 0 0 90)
			(unlocked yes)
			(layer "F.Fab")
			(hide yes)
			(effects
				(font
					(size 1 1)
					(thickness 0.15)
				)
			)
		)
		(property "Manufacturer" "AMD-Xilinx"
			(at 0 0 90)
			(unlocked yes)
			(layer "F.Fab")
			(hide yes)
			(effects
				(font
					(size 1 1)
					(thickness 0.15)
				)
			)
		)
		(property "Author" "Antmicro"
			(at 0 0 90)
			(unlocked yes)
			(layer "F.Fab")
			(hide yes)
			(effects
				(font
					(size 1 1)
					(thickness 0.15)
				)
			)
		)
		(property "License" "Apache-2.0"
			(at 0 0 90)
			(unlocked yes)
			(layer "F.Fab")
			(hide yes)
			(effects
				(font
					(size 1 1)
					(thickness 0.15)
				)
			)
		)
		(sheetname "/FPGA Config/")
		(sheetfile "fpga-config.kicad_sch")
		(attr smd)
		(pad "G18" smd circle
			(at 4.5 -6.5 90)
			(size 0.5 0.5)
			(layers "F.Cu" "F.Mask" "F.Paste")
			(net 797 "+1V8")
			(pinfunction "VCCO_67")
			(pintype "passive")
			(solder_mask_margin 0.075)
		)
		(pad "G19" smd circle
			(at 5.5 -6.5 90)
			(size 0.5 0.5)
			(layers "F.Cu" "F.Mask" "F.Paste")
			(net 672 "unconnected-(U34E-IO_T1U_N12_67-PadG19)")
			(pinfunction "IO_T1U_N12_67")
			(pintype "bidirectional+no_connect")
			(die_length 13.435)
			(solder_mask_margin 0.075)
		)
		(pad "G20" smd circle
			(at 6.5 -6.5 90)
			(size 0.5 0.5)
			(layers "F.Cu" "F.Mask" "F.Paste")
			(net 638 "/FPGA banks HP/SD.DAT0")
			(pinfunction "IO_L9P_T1L_N4_AD12P_67")
			(pintype "bidirectional")
			(die_length 12.173)
			(solder_mask_margin 0.075)
		)
		(pad "G21" smd circle
			(at 7.5 -6.5 90)
			(size 0.5 0.5)
			(layers "F.Cu" "F.Mask" "F.Paste")
			(net 639 "/FPGA banks HP/SD.DAT1")
			(pinfunction "IO_L9N_T1L_N5_AD12N_67")
			(pintype "bidirectional")
			(die_length 12.273)
			(solder_mask_margin 0.075)
		)
		(pad "G22" smd circle
			(at 8.5 -6.5 90)
			(size 0.5 0.5)
			(layers "F.Cu" "F.Mask" "F.Paste")
			(net 537 "unconnected-(U34D-IO_T2U_N12_66-PadG22)")
			(pinfunction "IO_T2U_N12_66")
			(pintype "bidirectional+no_connect")
			(die_length 11.631)
			(solder_mask_margin 0.075)
		)
		(pad "G23" smd circle
			(at 9.5 -6.5 90)
			(size 0.5 0.5)
			(layers "F.Cu" "F.Mask" "F.Paste")
			(net 1 "GND")
			(pinfunction "GND")
			(pintype "passive")
			(solder_mask_margin 0.075)
		)
		(pad "G24" smd circle
			(at 10.5 -6.5 90)
			(size 0.5 0.5)
			(layers "F.Cu" "F.Mask" "F.Paste")
			(net 147 "/DDR5 RDIMM/B.DQS2_P")
			(pinfunction "IO_L13P_T2L_N0_GC_QBC_66")
			(pintype "bidirectional")
			(die_length 13.798)
			(solder_mask_margin 0.075)
		)
		(pad "G25" smd circle
			(at 11.5 -6.5 90)
			(size 0.5 0.5)
			(layers "F.Cu" "F.Mask" "F.Paste")
			(net 148 "/DDR5 RDIMM/B.DQS2_N")
			(pinfunction "IO_L13N_T2L_N1_GC_QBC_66")
			(pintype "bidirectional")
			(die_length 13.716)
			(solder_mask_margin 0.075)
		)
		(pad "G26" smd circle
			(at 12.5 -6.5 90)
			(size 0.5 0.5)
			(layers "F.Cu" "F.Mask" "F.Paste")
			(net 122 "/DDR5 RDIMM/B.DQ20")
			(pinfunction "IO_L17N_T2U_N9_AD10N_66")
			(pintype "bidirectional")
			(die_length 14.685)
			(solder_mask_margin 0.075)
		)
		(pad "H1" smd circle
			(at -12.5 -5.5 90)
			(size 0.5 0.5)
			(layers "F.Cu" "F.Mask" "F.Paste")
			(net 648 "/FPGA MGT Interface/HDMI_FPGA.RX2_N")
			(pinfunction "MGTYRXN2_226")
			(pintype "input")
			(die_length 11.057)
			(solder_mask_margin 0.075)
		)
		(pad "H2" smd circle
			(at -11.5 -5.5 90)
			(size 0.5 0.5)
			(layers "F.Cu" "F.Mask" "F.Paste")
			(net 649 "/FPGA MGT Interface/HDMI_FPGA.RX2_P")
			(pinfunction "MGTYRXP2_226")
			(pintype "input")
			(die_length 11.047)
			(solder_mask_margin 0.075)
		)
		(pad "H3" smd circle
			(at -10.5 -5.5 90)
			(size 0.5 0.5)
			(layers "F.Cu" "F.Mask" "F.Paste")
			(net 1 "GND")
			(pinfunction "GND")
			(pintype "passive")
			(solder_mask_margin 0.075)
		)
		(pad "H4" smd circle
			(at -9.5 -5.5 90)
			(size 0.5 0.5)
			(layers "F.Cu" "F.Mask" "F.Paste")
			(net 1 "GND")
			(pinfunction "GND")
			(pintype "passive")
			(solder_mask_margin 0.075)
		)
		(pad "H5" smd circle
			(at -8.5 -5.5 90)
			(size 0.5 0.5)
			(layers "F.Cu" "F.Mask" "F.Paste")
			(net 172 "+1V2_MGTAVTT")
			(pinfunction "MGTAVTT_R")
			(pintype "passive")
			(solder_mask_margin 0.075)
		)
		(pad "H6" smd circle
			(at -7.5 -5.5 90)
			(size 0.5 0.5)
			(layers "F.Cu" "F.Mask" "F.Paste")
			(net 538 "unconnected-(U34L-NC-PadH6)")
			(pinfunction "NC")
			(pintype "no_connect")
			(solder_mask_margin 0.075)
		)
		(pad "H7" smd circle
			(at -6.5 -5.5 90)
			(size 0.5 0.5)
			(layers "F.Cu" "F.Mask" "F.Paste")
			(net 539 "unconnected-(U34L-NC-PadH7)")
			(pinfunction "NC")
			(pintype "no_connect")
			(solder_mask_margin 0.075)
		)
		(pad "H8" smd circle
			(at -5.5 -5.5 90)
			(size 0.5 0.5)
			(layers "F.Cu" "F.Mask" "F.Paste")
			(net 1 "GND")
			(pinfunction "GND")
			(pintype "passive")
			(solder_mask_margin 0.075)
		)
		(pad "H9" smd circle
			(at -4.5 -5.5 90)
			(size 0.5 0.5)
			(layers "F.Cu" "F.Mask" "F.Paste")
			(net 540 "unconnected-(U34G-IO_L3N_AD9N_86-PadH9)")
			(pinfunction "IO_L3N_AD9N_86")
			(pintype "bidirectional+no_connect")
			(die_length 15.853)
			(solder_mask_margin 0.075)
		)
		(pad "H10" smd circle
			(at -3.5 -5.5 90)
			(size 0.5 0.5)
			(layers "F.Cu" "F.Mask" "F.Paste")
			(net 151 "+3V3")
			(pinfunction "VCCO_86")
			(pintype "passive")
			(solder_mask_margin 0.075)
		)
		(pad "H11" smd circle
			(at -2.5 -5.5 90)
			(size 0.5 0.5)
			(layers "F.Cu" "F.Mask" "F.Paste")
			(net 541 "unconnected-(U34G-IO_L4P_AD8P_86-PadH11)")
			(pinfunction "IO_L4P_AD8P_86")
			(pintype "bidirectional+no_connect")
			(die_length 13.526)
			(solder_mask_margin 0.075)
		)
		(pad "H12" smd circle
			(at -1.5 -5.5 90)
			(size 0.5 0.5)
			(layers "F.Cu" "F.Mask" "F.Paste")
			(net 550 "/FPGA banks HD/HDMI_IN_I2C.SCL")
			(pinfunction "IO_L1N_AD15N_87")
			(pintype "bidirectional")
			(die_length 11.289)
			(solder_mask_margin 0.075)
		)
		(pad "H13" smd circle
			(at -0.5 -5.5 90)
			(size 0.5 0.5)
			(layers "F.Cu" "F.Mask" "F.Paste")
			(net 554 "/FPGA banks HD/HDMI_OUT_I2C.SCL")
			(pinfunction "IO_L2N_AD14N_87")
			(pintype "bidirectional")
			(die_length 9.307)
			(solder_mask_margin 0.075)
		)
		(pad "H14" smd circle
			(at 0.5 -5.5 90)
			(size 0.5 0.5)
			(layers "F.Cu" "F.Mask" "F.Paste")
			(net 799 "unconnected-(U34H-IO_L3P_AD13P_87-PadH14)")
			(pinfunction "IO_L3P_AD13P_87")
			(pintype "bidirectional+no_connect")
			(die_length 9.918)
			(solder_mask_margin 0.075)
		)
		(pad "H15" smd circle
			(at 1.5 -5.5 90)
			(size 0.5 0.5)
			(layers "F.Cu" "F.Mask" "F.Paste")
			(net 151 "+3V3")
			(pinfunction "VCCO_87")
			(pintype "passive")
			(solder_mask_margin 0.075)
		)
		(pad "H16" smd circle
			(at 2.5 -5.5 90)
			(size 0.5 0.5)
			(layers "F.Cu" "F.Mask" "F.Paste")
			(net 622 "/FPGA banks HP/HyperRAM.DQ0")
			(pinfunction "IO_L5P_T0U_N8_AD14P_67")
			(pintype "bidirectional")
			(die_length 12.856)
			(solder_mask_margin 0.075)
		)
		(pad "H17" smd circle
			(at 3.5 -5.5 90)
			(size 0.5 0.5)
			(layers "F.Cu" "F.Mask" "F.Paste")
			(net 619 "/FPGA banks HP/HyperRAM.DQ5")
			(pinfunction "IO_L2P_T0L_N2_67")
			(pintype "bidirectional")
			(die_length 12.955)
			(solder_mask_margin 0.075)
		)
		(pad "H18" smd circle
			(at 4.5 -5.5 90)
			(size 0.5 0.5)
			(layers "F.Cu" "F.Mask" "F.Paste")
			(net 618 "/FPGA banks HP/HyperRAM.~{CS}")
			(pinfunction "IO_L7P_T1L_N0_QBC_AD13P_67")
			(pintype "bidirectional")
			(die_length 12.354)
			(solder_mask_margin 0.075)
		)
		(pad "H19" smd circle
			(at 5.5 -5.5 90)
			(size 0.5 0.5)
			(layers "F.Cu" "F.Mask" "F.Paste")
			(net 637 "/FPGA banks HP/SD.CMD")
			(pinfunction "IO_L7N_T1L_N1_QBC_AD13N_67")
			(pintype "bidirectional")
			(die_length 12.276)
			(solder_mask_margin 0.075)
		)
		(pad "H20" smd circle
			(at 6.5 -5.5 90)
			(size 0.5 0.5)
			(layers "F.Cu" "F.Mask" "F.Paste")
			(net 1 "GND")
			(pinfunction "GND")
			(pintype "passive")
			(solder_mask_margin 0.075)
		)
		(pad "H21" smd circle
			(at 7.5 -5.5 90)
			(size 0.5 0.5)
			(layers "F.Cu" "F.Mask" "F.Paste")
			(net 454 "/DDR5 RDIMM/B.DQ23")
			(pinfunction "IO_L18P_T2U_N10_AD2P_66")
			(pintype "bidirectional")
			(die_length 11.698)
			(solder_mask_margin 0.075)
		)
		(pad "H22" smd circle
			(at 8.5 -5.5 90)
			(size 0.5 0.5)
			(layers "F.Cu" "F.Mask" "F.Paste")
			(net 123 "/DDR5 RDIMM/B.DQ21")
			(pinfunction "IO_L18N_T2U_N11_AD2N_66")
			(pintype "bidirectional")
			(die_length 11.516)
			(solder_mask_margin 0.075)
		)
		(pad "H23" smd circle
			(at 9.5 -5.5 90)
			(size 0.5 0.5)
			(layers "F.Cu" "F.Mask" "F.Paste")
			(net 118 "/DDR5 RDIMM/B.DQ16")
			(pinfunction "IO_L14P_T2L_N2_GC_66")
			(pintype "bidirectional")
			(die_length 11.537)
			(solder_mask_margin 0.075)
		)
		(pad "H24" smd circle
			(at 10.5 -5.5 90)
			(size 0.5 0.5)
			(layers "F.Cu" "F.Mask" "F.Paste")
			(net 360 "/DDR5 RDIMM/B.DQ18")
			(pinfunction "IO_L14N_T2L_N3_GC_66")
			(pintype "bidirectional")
			(die_length 11.55)
			(solder_mask_margin 0.075)
		)
		(pad "H25" smd circle
			(at 11.5 -5.5 90)
			(size 0.5 0.5)
			(layers "F.Cu" "F.Mask" "F.Paste")
			(net 687 "VDDQ")
			(pinfunction "VCCO_66")
			(pintype "passive")
			(solder_mask_margin 0.075)
		)
		(pad "H26" smd circle
			(at 12.5 -5.5 90)
			(size 0.5 0.5)
			(layers "F.Cu" "F.Mask" "F.Paste")
			(net 453 "/DDR5 RDIMM/B.DQ22")
			(pinfunction "IO_L17P_T2U_N8_AD10P_66")
			(pintype "bidirectional")
			(die_length 14.98)
			(solder_mask_margin 0.075)
		)
		(pad "J1" smd circle
			(at -12.5 -4.5 90)
			(size 0.5 0.5)
			(layers "F.Cu" "F.Mask" "F.Paste")
			(net 1 "GND")
			(pinfunction "GND")
			(pintype "passive")
			(solder_mask_margin 0.075)
		)
		(pad "J2" smd circle
			(at -11.5 -4.5 90)
			(size 0.5 0.5)
			(layers "F.Cu" "F.Mask" "F.Paste")
			(net 1 "GND")
			(pinfunction "GND")
			(pintype "passive")
			(solder_mask_margin 0.075)
		)
		(pad "J3" smd circle
			(at -10.5 -4.5 90)
			(size 0.5 0.5)
			(layers "F.Cu" "F.Mask" "F.Paste")
			(net 1 "GND")
			(pinfunction "GND")
			(pintype "passive")
			(solder_mask_margin 0.075)
		)
		(pad "J4" smd circle
			(at -9.5 -4.5 90)
			(size 0.5 0.5)
			(layers "F.Cu" "F.Mask" "F.Paste")
			(net 627 "/FPGA MGT Interface/HDMI_FPGA.TX2_N")
			(pinfunction "MGTYTXN2_226")
			(pintype "output")
			(die_length 9.068)
			(solder_mask_margin 0.075)
		)
		(pad "J5" smd circle
			(at -8.5 -4.5 90)
			(size 0.5 0.5)
			(layers "F.Cu" "F.Mask" "F.Paste")
			(net 628 "/FPGA MGT Interface/HDMI_FPGA.TX2_P")
			(pinfunction "MGTYTXP2_226")
			(pintype "output")
			(die_length 9.085)
			(solder_mask_margin 0.075)
		)
		(pad "J6" smd circle
			(at -7.5 -4.5 90)
			(size 0.5 0.5)
			(layers "F.Cu" "F.Mask" "F.Paste")
			(net 1 "GND")
			(pinfunction "GND")
			(pintype "passive")
			(solder_mask_margin 0.075)
		)
		(pad "J7" smd circle
			(at -6.5 -4.5 90)
			(size 0.5 0.5)
			(layers "F.Cu" "F.Mask" "F.Paste")
			(net 820 "+0V9_MGTAVCC")
			(pinfunction "MGTAVCC_R")
			(pintype "passive")
			(solder_mask_margin 0.075)
		)
		(pad "J8" smd circle
			(at -5.5 -4.5 90)
			(size 0.5 0.5)
			(layers "F.Cu" "F.Mask" "F.Paste")
			(net 1 "GND")
			(pinfunction "GND")
			(pintype "passive")
			(solder_mask_margin 0.075)
		)
		(pad "J9" smd circle
			(at -4.5 -4.5 90)
			(size 0.5 0.5)
			(layers "F.Cu" "F.Mask" "F.Paste")
			(net 697 "/FPGA banks HD/USR_LED1")
			(pinfunction "IO_L3P_AD9P_86")
			(pintype "bidirectional")
			(die_length 15.627)
			(solder_mask_margin 0.075)
		)
		(pad "J10" smd circle
			(at -3.5 -4.5 90)
			(size 0.5 0.5)
			(layers "F.Cu" "F.Mask" "F.Paste")
			(net 698 "/FPGA banks HD/USR_LED2")
			(pinfunction "IO_L2N_AD10N_86")
			(pintype "bidirectional")
			(die_length 14.793)
			(solder_mask_margin 0.075)
		)
		(pad "J11" smd circle
			(at -2.5 -4.5 90)
			(size 0.5 0.5)
			(layers "F.Cu" "F.Mask" "F.Paste")
			(net 699 "/FPGA banks HD/USR_LED3")
			(pinfunction "IO_L2P_AD10P_86")
			(pintype "bidirectional")
			(die_length 14.115)
			(solder_mask_margin 0.075)
		)
		(pad "J12" smd circle
			(at -1.5 -4.5 90)
			(size 0.5 0.5)
			(layers "F.Cu" "F.Mask" "F.Paste")
			(net 555 "/FPGA banks HD/HDMI_IN_I2C.SDA")
			(pinfunction "IO_L1P_AD15P_87")
			(pintype "bidirectional")
			(die_length 11.407)
			(solder_mask_margin 0.075)
		)
		(pad "J13" smd circle
			(at -0.5 -4.5 90)
			(size 0.5 0.5)
			(layers "F.Cu" "F.Mask" "F.Paste")
			(net 644 "/FPGA banks HD/HDMI_OUT_I2C.SDA")
			(pinfunction "IO_L2P_AD14P_87")
			(pintype "bidirectional")
			(die_length 9.54)
			(solder_mask_margin 0.075)
		)
		(pad "J14" smd circle
			(at 0.5 -4.5 90)
			(size 0.5 0.5)
			(layers "F.Cu" "F.Mask" "F.Paste")
			(net 800 "unconnected-(U34H-IO_L4N_AD12N_87-PadJ14)")
			(pinfunction "IO_L4N_AD12N_87")
			(pintype "bidirectional+no_connect")
			(die_length 9.364)
			(solder_mask_margin 0.075)
		)
		(pad "J15" smd circle
			(at 1.5 -4.5 90)
			(size 0.5 0.5)
			(layers "F.Cu" "F.Mask" "F.Paste")
			(net 801 "unconnected-(U34H-IO_L4P_AD12P_87-PadJ15)")
			(pinfunction "IO_L4P_AD12P_87")
			(pintype "bidirectional+no_connect")
			(die_length 9.373)
			(solder_mask_margin 0.075)
		)
		(pad "J16" smd circle
			(at 2.5 -4.5 90)
			(size 0.5 0.5)
			(layers "F.Cu" "F.Mask" "F.Paste")
			(net 546 "/FPGA banks HP/VREF_67")
			(pinfunction "VREF_67")
			(pintype "input")
			(solder_mask_margin 0.075)
		)
		(pad "J17" smd circle
			(at 3.5 -4.5 90)
			(size 0.5 0.5)
			(layers "F.Cu" "F.Mask" "F.Paste")
			(net 1 "GND")
			(pinfunction "GND")
			(pintype "passive")
			(solder_mask_margin 0.075)
		)
		(pad "J18" smd circle
			(at 4.5 -4.5 90)
			(size 0.5 0.5)
			(layers "F.Cu" "F.Mask" "F.Paste")
			(net 545 "/FPGA banks HP/VREF_66")
			(pinfunction "VREF_66")
			(pintype "input")
			(solder_mask_margin 0.075)
		)
		(pad "J19" smd circle
			(at 5.5 -4.5 90)
			(size 0.5 0.5)
			(layers "F.Cu" "F.Mask" "F.Paste")
			(net 212 "/DDR5 RDIMM/B.DQ2")
			(pinfunction "IO_L3P_T0L_N4_AD15P_66")
			(pintype "bidirectional")
			(die_length 18.466)
			(solder_mask_margin 0.075)
		)
		(pad "J20" smd circle
			(at 6.5 -4.5 90)
			(size 0.5 0.5)
			(layers "F.Cu" "F.Mask" "F.Paste")
			(net 213 "/DDR5 RDIMM/B.DQ3")
			(pinfunction "IO_L3N_T0L_N5_AD15N_66")
			(pintype "bidirectional")
			(die_length 16.89)
			(solder_mask_margin 0.075)
		)
		(pad "J21" smd circle
			(at 7.5 -4.5 90)
			(size 0.5 0.5)
			(layers "F.Cu" "F.Mask" "F.Paste")
			(net 218 "/DDR5 RDIMM/B.DQ7")
			(pinfunction "IO_L5N_T0U_N9_AD14N_66")
			(pintype "bidirectional")
			(die_length 15.754)
			(solder_mask_margin 0.075)
		)
		(pad "J22" smd circle
			(at 8.5 -4.5 90)
			(size 0.5 0.5)
			(layers "F.Cu" "F.Mask" "F.Paste")
			(net 687 "VDDQ")
			(pinfunction "VCCO_66")
			(pintype "passive")
			(solder_mask_margin 0.075)
		)
		(pad "J23" smd circle
			(at 9.5 -4.5 90)
			(size 0.5 0.5)
			(layers "F.Cu" "F.Mask" "F.Paste")
			(net 358 "/DDR5 RDIMM/B.DQ14")
			(pinfunction "IO_L12P_T1U_N10_GC_66")
			(pintype "bidirectional")
			(die_length 11.034)
			(solder_mask_margin 0.075)
		)
		(pad "J24" smd circle
			(at 10.5 -4.5 90)
			(size 0.5 0.5)
			(layers "F.Cu" "F.Mask" "F.Paste")
			(net 116 "/DDR5 RDIMM/B.DQ12")
			(pinfunction "IO_L12N_T1U_N11_GC_66")
			(pintype "bidirectional")
			(die_length 10.935)
			(solder_mask_margin 0.075)
		)
		(pad "J25" smd circle
			(at 11.5 -4.5 90)
			(size 0.5 0.5)
			(layers "F.Cu" "F.Mask" "F.Paste")
			(net 119 "/DDR5 RDIMM/B.DQ17")
			(pinfunction "IO_L15P_T2L_N4_AD11P_66")
			(pintype "bidirectional")
			(die_length 15.524)
			(solder_mask_margin 0.075)
		)
		(pad "J26" smd circle
			(at 12.5 -4.5 90)
			(size 0.5 0.5)
			(layers "F.Cu" "F.Mask" "F.Paste")
			(net 450 "/DDR5 RDIMM/B.DQ19")
			(pinfunction "IO_L15N_T2L_N5_AD11N_66")
			(pintype "bidirectional")
			(die_length 15.495)
			(solder_mask_margin 0.075)
		)
		(pad "K1" smd circle
			(at -12.5 -3.5 90)
			(size 0.5 0.5)
			(layers "F.Cu" "F.Mask" "F.Paste")
			(net 650 "/FPGA MGT Interface/HDMI_FPGA.RX1_N")
			(pinfunction "MGTYRXN1_226")
			(pintype "input")
			(die_length 9.924)
			(solder_mask_margin 0.075)
		)
		(pad "K2" smd circle
			(at -11.5 -3.5 90)
			(size 0.5 0.5)
			(layers "F.Cu" "F.Mask" "F.Paste")
			(net 651 "/FPGA MGT Interface/HDMI_FPGA.RX1_P")
			(pinfunction "MGTYRXP1_226")
			(pintype "input")
			(die_length 9.903)
			(solder_mask_margin 0.075)
		)
		(pad "K3" smd circle
			(at -10.5 -3.5 90)
			(size 0.5 0.5)
			(layers "F.Cu" "F.Mask" "F.Paste")
			(net 1 "GND")
			(pinfunction "GND")
			(pintype "passive")
			(solder_mask_margin 0.075)
		)
		(pad "K4" smd circle
			(at -9.5 -3.5 90)
			(size 0.5 0.5)
			(layers "F.Cu" "F.Mask" "F.Paste")
			(net 1 "GND")
			(pinfunction "GND")
			(pintype "passive")
			(solder_mask_margin 0.075)
		)
	)
)
